(kicad_pcb
	(version 20260206)
	(generator "pcbnew")
	(generator_version "10.0")
	(general
		(thickness 1.6)
		(legacy_teardrops no)
	)
	(paper "A4")
	(title_block
		(title "Bryce Canyon_IOM_M2_16342-2_OCP.brd")
		(comment 1 "Bryce Canyon / footprints 880-887 of 1146")
	)
	(layers
		(0 "F.Cu" signal "TOP")
		(4 "In1.Cu" signal "L2GND")
		(6 "In2.Cu" signal "L3")
		(8 "In3.Cu" signal "L4VCC")
		(10 "In4.Cu" signal "L5VCC")
		(12 "In5.Cu" signal "L6")
		(14 "In6.Cu" signal "L7GND")
		(2 "B.Cu" signal "BOTTOM")
		(9 "F.Adhes" user "F.Adhesive")
		(11 "B.Adhes" user "B.Adhesive")
		(13 "F.Paste" user "Package Geometry/Pastemask Top")
		(15 "B.Paste" user "Package Geometry/Pastemask Bottom")
		(5 "F.SilkS" user "Ref Des/Silkscreen Top")
		(7 "B.SilkS" user "Ref Des/Silkscreen Bottom")
		(1 "F.Mask" user "Board Geometry/Soldermask Top")
		(3 "B.Mask" user "Board Geometry/Soldermask Bottom")
		(17 "Dwgs.User" user "User.Drawings")
		(19 "Cmts.User" user "User.Comments")
		(21 "Eco1.User" user "User.Eco1")
		(23 "Eco2.User" user "User.Eco2")
		(25 "Edge.Cuts" user "Board Geometry/Outline")
		(27 "Margin" user)
		(31 "F.CrtYd" user "Package Geometry/Place Bound Top")
		(29 "B.CrtYd" user "Package Geometry/Place Bound Bottom")
		(35 "F.Fab" user "Ref Des/Assembly Top")
		(33 "B.Fab" user "Ref Des/Assembly Bottom")
	)
	(footprint ""
		(layer "B.Cu")
		(at 35.941 -157.5308 -90)
		(property "Reference" "R706"
			(at 0 0 90)
			(layer "B.SilkS")
			(hide yes)
			(effects
				(font
					(size 1.27 1.27)
				)
				(justify mirror)
			)
		)
		(property "Value" "4K7R2F-GP"
			(at -0.064008 -3.993896 270)
			(unlocked yes)
			(layer "B.Fab")
			(hide yes)
			(effects
				(font
					(size 1.016 1.016)
					(thickness 0.1524)
				)
				(justify mirror)
			)
		)
		(property "Device Type" "R402H16"
			(at -0.064008 -5.517896 270)
			(unlocked yes)
			(layer "B.Fab")
			(hide yes)
			(effects
				(font
					(size 1.016 1.016)
					(thickness 0.1524)
				)
				(justify mirror)
			)
		)
		(duplicate_pad_numbers_are_jumpers no)
		(fp_line
			(start -0.508 -0.9398)
			(end 0.508 -0.9398)
			(stroke
				(width 0.1524)
				(type default)
			)
			(layer "B.SilkS")
		)
		(fp_line
			(start 0.508 -0.9398)
			(end 0.508 0.9398)
			(stroke
				(width 0.1524)
				(type default)
			)
			(layer "B.SilkS")
		)
		(fp_rect
			(start 0.508 0.9398)
			(end -0.508 -0.9398)
			(stroke
				(width 0)
				(type default)
			)
			(fill no)
			(layer "B.CrtYd")
		)
		(fp_rect
			(start 0.508 0.9398)
			(end -0.508 -0.9398)
			(stroke
				(width 0)
				(type default)
			)
			(fill no)
			(layer "B.Fab")
		)
		(pad "1" smd custom
			(at 0 -0.4445 90)
			(size 0.1397 0.1397)
			(layers "B.Cu" "B.Mask" "B.Paste")
			(net "IOM_TYPE3")
			(options
				(clearance outline)
				(anchor circle)
			)
			(primitives
				(gr_poly
					(pts
						(arc
							(start -0.1778 0.2794)
							(mid -0.249642 0.249642)
							(end -0.2794 0.1778)
						)
						(arc
							(start -0.2794 -0.1778)
							(mid -0.249642 -0.249642)
							(end -0.1778 -0.2794)
						)
						(arc
							(start 0.1778 -0.2794)
							(mid 0.249642 -0.249642)
							(end 0.2794 -0.1778)
						)
						(arc
							(start 0.2794 0.1778)
							(mid 0.249642 0.249642)
							(end 0.1778 0.2794)
						)
					)
					(width 0)
					(fill yes)
				)
			)
		)
		(pad "2" smd custom
			(at 0 0.4445 90)
			(size 0.1397 0.1397)
			(layers "B.Cu" "B.Mask" "B.Paste")
			(net "GND")
			(options
				(clearance outline)
				(anchor circle)
			)
			(primitives
				(gr_poly
					(pts
						(arc
							(start -0.1778 0.2794)
							(mid -0.249642 0.249642)
							(end -0.2794 0.1778)
						)
						(arc
							(start -0.2794 -0.1778)
							(mid -0.249642 -0.249642)
							(end -0.1778 -0.2794)
						)
						(arc
							(start 0.1778 -0.2794)
							(mid 0.249642 -0.249642)
							(end 0.2794 -0.1778)
						)
						(arc
							(start 0.2794 0.1778)
							(mid 0.249642 0.249642)
							(end 0.1778 0.2794)
						)
					)
					(width 0)
					(fill yes)
				)
			)
		)
	)
	(footprint ""
		(layer "B.Cu")
		(at 52.78628 -144.99844)
		(property "Reference" "TP52"
			(at 0 0 0)
			(layer "B.SilkS")
			(hide yes)
			(effects
				(font
					(size 1.27 1.27)
				)
				(justify mirror)
			)
		)
		(property "Value" "TPAD28-2-GP"
			(at 0.0127 -1.6637 0)
			(unlocked yes)
			(layer "B.Fab")
			(hide yes)
			(effects
				(font
					(size 1.016 1.016)
					(thickness 0.1524)
				)
				(justify mirror)
			)
		)
		(property "Device Type" "TPAD28"
			(at 0.0127 -3.1877 0)
			(unlocked yes)
			(layer "B.Fab")
			(hide yes)
			(effects
				(font
					(size 1.016 1.016)
					(thickness 0.1524)
				)
				(justify mirror)
			)
		)
		(duplicate_pad_numbers_are_jumpers no)
		(fp_poly
			(pts
				(arc
					(start 0.3556 0)
					(mid -0.3556 0)
					(end 0.3556 0)
				)
			)
			(stroke
				(width 0)
				(type default)
			)
			(fill no)
			(layer "B.CrtYd")
		)
		(fp_poly
			(pts
				(arc
					(start 0.6096 0)
					(mid -0.6096 0)
					(end 0.6096 0)
				)
			)
			(stroke
				(width 0)
				(type default)
			)
			(fill no)
			(layer "B.Fab")
		)
		(pad "1" smd circle
			(at 0 0 180)
			(size 0.7112 0.7112)
			(layers "B.Cu" "B.Mask" "B.Paste")
			(net "RMII_BMC_MDIO_R")
		)
	)
	(footprint ""
		(layer "B.Cu")
		(at 91.2114 -169.05732 90)
		(property "Reference" "R795"
			(at 0 0 90)
			(layer "B.SilkS")
			(hide yes)
			(effects
				(font
					(size 1.27 1.27)
				)
				(justify mirror)
			)
		)
		(property "Value" "0R2J-2-GP"
			(at -0.064008 -3.993896 90)
			(unlocked yes)
			(layer "B.Fab")
			(hide yes)
			(effects
				(font
					(size 1.016 1.016)
					(thickness 0.1524)
				)
				(justify mirror)
			)
		)
		(property "Device Type" "R402H16"
			(at -0.064008 -5.517896 90)
			(unlocked yes)
			(layer "B.Fab")
			(hide yes)
			(effects
				(font
					(size 1.016 1.016)
					(thickness 0.1524)
				)
				(justify mirror)
			)
		)
		(duplicate_pad_numbers_are_jumpers no)
		(fp_line
			(start 0.508 -0.9398)
			(end 0.508 0.9398)
			(stroke
				(width 0.1524)
				(type default)
			)
			(layer "B.SilkS")
		)
		(fp_line
			(start -0.508 -0.9398)
			(end 0.508 -0.9398)
			(stroke
				(width 0.1524)
				(type default)
			)
			(layer "B.SilkS")
		)
		(fp_rect
			(start 0.508 0.9398)
			(end -0.508 -0.9398)
			(stroke
				(width 0)
				(type default)
			)
			(fill no)
			(layer "B.CrtYd")
		)
		(fp_rect
			(start 0.508 0.9398)
			(end -0.508 -0.9398)
			(stroke
				(width 0)
				(type default)
			)
			(fill no)
			(layer "B.Fab")
		)
		(pad "1" smd custom
			(at 0 -0.4445 270)
			(size 0.1397 0.1397)
			(layers "B.Cu" "B.Mask" "B.Paste")
			(net "UART_COMP_IN_RX_AND_R")
			(options
				(clearance outline)
				(anchor circle)
			)
			(primitives
				(gr_poly
					(pts
						(arc
							(start -0.1778 0.2794)
							(mid -0.249642 0.249642)
							(end -0.2794 0.1778)
						)
						(arc
							(start -0.2794 -0.1778)
							(mid -0.249642 -0.249642)
							(end -0.1778 -0.2794)
						)
						(arc
							(start 0.1778 -0.2794)
							(mid 0.249642 -0.249642)
							(end 0.2794 -0.1778)
						)
						(arc
							(start 0.2794 0.1778)
							(mid 0.249642 0.249642)
							(end 0.1778 0.2794)
						)
					)
					(width 0)
					(fill yes)
				)
			)
		)
		(pad "2" smd custom
			(at 0 0.4445 270)
			(size 0.1397 0.1397)
			(layers "B.Cu" "B.Mask" "B.Paste")
			(net "UART_COMP_IN_RX_AND")
			(options
				(clearance outline)
				(anchor circle)
			)
			(primitives
				(gr_poly
					(pts
						(arc
							(start -0.1778 0.2794)
							(mid -0.249642 0.249642)
							(end -0.2794 0.1778)
						)
						(arc
							(start -0.2794 -0.1778)
							(mid -0.249642 -0.249642)
							(end -0.1778 -0.2794)
						)
						(arc
							(start 0.1778 -0.2794)
							(mid 0.249642 -0.249642)
							(end 0.2794 -0.1778)
						)
						(arc
							(start 0.2794 0.1778)
							(mid 0.249642 0.249642)
							(end 0.1778 0.2794)
						)
					)
					(width 0)
					(fill yes)
				)
			)
		)
	)
	(footprint ""
		(layer "B.Cu")
		(at 52.7304 -126.33452 180)
		(property "Reference" "C505"
			(at 0 0 0)
			(layer "B.SilkS")
			(hide yes)
			(effects
				(font
					(size 1.27 1.27)
				)
				(justify mirror)
			)
		)
		(property "Value" "SCD1U16V2KX-3GP"
			(at -1.1811 -2.7051 180)
			(unlocked yes)
			(layer "B.Fab")
			(hide yes)
			(effects
				(font
					(size 1.016 1.016)
					(thickness 0.1524)
				)
				(justify mirror)
			)
		)
		(property "Device Type" "C402H22"
			(at -1.1811 -4.2291 180)
			(unlocked yes)
			(layer "B.Fab")
			(hide yes)
			(effects
				(font
					(size 1.016 1.016)
					(thickness 0.1524)
				)
				(justify mirror)
			)
		)
		(duplicate_pad_numbers_are_jumpers no)
		(fp_rect
			(start 0.4318 0.9525)
			(end -0.4318 -0.9525)
			(stroke
				(width 0)
				(type default)
			)
			(fill no)
			(layer "B.CrtYd")
		)
		(fp_rect
			(start 0.4318 0.9525)
			(end -0.4318 -0.9525)
			(stroke
				(width 0)
				(type default)
			)
			(fill no)
			(layer "B.Fab")
		)
		(pad "1" smd custom
			(at 0 -0.4445)
			(size 0.1524 0.1524)
			(layers "B.Cu" "B.Mask" "B.Paste")
			(net "P3V3_STBY")
			(options
				(clearance outline)
				(anchor circle)
			)
			(primitives
				(gr_poly
					(pts
						(arc
							(start 0.3048 0.2032)
							(mid 0.275042 0.275042)
							(end 0.2032 0.3048)
						)
						(arc
							(start -0.2032 0.3048)
							(mid -0.275042 0.275042)
							(end -0.3048 0.2032)
						)
						(arc
							(start -0.3048 -0.2032)
							(mid -0.275042 -0.275042)
							(end -0.2032 -0.3048)
						)
						(arc
							(start 0.2032 -0.3048)
							(mid 0.275042 -0.275042)
							(end 0.3048 -0.2032)
						)
					)
					(width 0)
					(fill yes)
				)
			)
		)
		(pad "2" smd custom
			(at 0 0.4445)
			(size 0.1524 0.1524)
			(layers "B.Cu" "B.Mask" "B.Paste")
			(net "GND")
			(options
				(clearance outline)
				(anchor circle)
			)
			(primitives
				(gr_poly
					(pts
						(arc
							(start 0.3048 0.2032)
							(mid 0.275042 0.275042)
							(end 0.2032 0.3048)
						)
						(arc
							(start -0.2032 0.3048)
							(mid -0.275042 0.275042)
							(end -0.3048 0.2032)
						)
						(arc
							(start -0.3048 -0.2032)
							(mid -0.275042 -0.275042)
							(end -0.2032 -0.3048)
						)
						(arc
							(start 0.2032 -0.3048)
							(mid 0.275042 -0.275042)
							(end 0.3048 -0.2032)
						)
					)
					(width 0)
					(fill yes)
				)
			)
		)
	)
	(footprint ""
		(layer "B.Cu")
		(at 12.11199 -142.463266 90)
		(property "Reference" "R212"
			(at 0 0 90)
			(layer "B.SilkS")
			(hide yes)
			(effects
				(font
					(size 1.27 1.27)
				)
				(justify mirror)
			)
		)
		(property "Value" "120R2F-GP"
			(at -0.064008 -3.993896 90)
			(unlocked yes)
			(layer "B.Fab")
			(hide yes)
			(effects
				(font
					(size 1.016 1.016)
					(thickness 0.1524)
				)
				(justify mirror)
			)
		)
		(property "Device Type" "R402H16"
			(at -0.064008 -5.517896 90)
			(unlocked yes)
			(layer "B.Fab")
			(hide yes)
			(effects
				(font
					(size 1.016 1.016)
					(thickness 0.1524)
				)
				(justify mirror)
			)
		)
		(duplicate_pad_numbers_are_jumpers no)
		(fp_line
			(start 0.508 -0.9398)
			(end 0.508 0.9398)
			(stroke
				(width 0.1524)
				(type default)
			)
			(layer "B.SilkS")
		)
		(fp_line
			(start -0.508 -0.9398)
			(end 0.508 -0.9398)
			(stroke
				(width 0.1524)
				(type default)
			)
			(layer "B.SilkS")
		)
		(fp_rect
			(start 0.508 0.9398)
			(end -0.508 -0.9398)
			(stroke
				(width 0)
				(type default)
			)
			(fill no)
			(layer "B.CrtYd")
		)
		(fp_rect
			(start 0.508 0.9398)
			(end -0.508 -0.9398)
			(stroke
				(width 0)
				(type default)
			)
			(fill no)
			(layer "B.Fab")
		)
		(pad "1" smd custom
			(at 0 -0.4445 270)
			(size 0.1397 0.1397)
			(layers "B.Cu" "B.Mask" "B.Paste")
			(net "MEMODT")
			(options
				(clearance outline)
				(anchor circle)
			)
			(primitives
				(gr_poly
					(pts
						(arc
							(start -0.1778 0.2794)
							(mid -0.249642 0.249642)
							(end -0.2794 0.1778)
						)
						(arc
							(start -0.2794 -0.1778)
							(mid -0.249642 -0.249642)
							(end -0.1778 -0.2794)
						)
						(arc
							(start 0.1778 -0.2794)
							(mid 0.249642 -0.249642)
							(end 0.2794 -0.1778)
						)
						(arc
							(start 0.2794 0.1778)
							(mid 0.249642 0.249642)
							(end 0.1778 0.2794)
						)
					)
					(width 0)
					(fill yes)
				)
			)
		)
		(pad "2" smd custom
			(at 0 0.4445 270)
			(size 0.1397 0.1397)
			(layers "B.Cu" "B.Mask" "B.Paste")
			(net "P1V2_STBY")
			(options
				(clearance outline)
				(anchor circle)
			)
			(primitives
				(gr_poly
					(pts
						(arc
							(start -0.1778 0.2794)
							(mid -0.249642 0.249642)
							(end -0.2794 0.1778)
						)
						(arc
							(start -0.2794 -0.1778)
							(mid -0.249642 -0.249642)
							(end -0.1778 -0.2794)
						)
						(arc
							(start 0.1778 -0.2794)
							(mid 0.249642 -0.249642)
							(end 0.2794 -0.1778)
						)
						(arc
							(start 0.2794 0.1778)
							(mid 0.249642 0.249642)
							(end 0.1778 0.2794)
						)
					)
					(width 0)
					(fill yes)
				)
			)
		)
	)
	(footprint ""
		(layer "B.Cu")
		(at 200.829418 -130.391408 180)
		(property "Reference" "C607"
			(at 0 0 0)
			(layer "B.SilkS")
			(hide yes)
			(effects
				(font
					(size 1.27 1.27)
				)
				(justify mirror)
			)
		)
		(property "Value" "SCD1U16V2KX-3GP"
			(at -1.1811 -2.7051 180)
			(unlocked yes)
			(layer "B.Fab")
			(hide yes)
			(effects
				(font
					(size 1.016 1.016)
					(thickness 0.1524)
				)
				(justify mirror)
			)
		)
		(property "Device Type" "C402H22"
			(at -1.1811 -4.2291 180)
			(unlocked yes)
			(layer "B.Fab")
			(hide yes)
			(effects
				(font
					(size 1.016 1.016)
					(thickness 0.1524)
				)
				(justify mirror)
			)
		)
		(duplicate_pad_numbers_are_jumpers no)
		(fp_rect
			(start 0.4318 0.9525)
			(end -0.4318 -0.9525)
			(stroke
				(width 0)
				(type default)
			)
			(fill no)
			(layer "B.CrtYd")
		)
		(fp_rect
			(start 0.4318 0.9525)
			(end -0.4318 -0.9525)
			(stroke
				(width 0)
				(type default)
			)
			(fill no)
			(layer "B.Fab")
		)
		(pad "1" smd custom
			(at 0 -0.4445)
			(size 0.1524 0.1524)
			(layers "B.Cu" "B.Mask" "B.Paste")
			(net "P3V3_M2")
			(options
				(clearance outline)
				(anchor circle)
			)
			(primitives
				(gr_poly
					(pts
						(arc
							(start 0.3048 0.2032)
							(mid 0.275042 0.275042)
							(end 0.2032 0.3048)
						)
						(arc
							(start -0.2032 0.3048)
							(mid -0.275042 0.275042)
							(end -0.3048 0.2032)
						)
						(arc
							(start -0.3048 -0.2032)
							(mid -0.275042 -0.275042)
							(end -0.2032 -0.3048)
						)
						(arc
							(start 0.2032 -0.3048)
							(mid 0.275042 -0.275042)
							(end 0.3048 -0.2032)
						)
					)
					(width 0)
					(fill yes)
				)
			)
		)
		(pad "2" smd custom
			(at 0 0.4445)
			(size 0.1524 0.1524)
			(layers "B.Cu" "B.Mask" "B.Paste")
			(net "GND")
			(options
				(clearance outline)
				(anchor circle)
			)
			(primitives
				(gr_poly
					(pts
						(arc
							(start 0.3048 0.2032)
							(mid 0.275042 0.275042)
							(end 0.2032 0.3048)
						)
						(arc
							(start -0.2032 0.3048)
							(mid -0.275042 0.275042)
							(end -0.3048 0.2032)
						)
						(arc
							(start -0.3048 -0.2032)
							(mid -0.275042 -0.275042)
							(end -0.2032 -0.3048)
						)
						(arc
							(start 0.2032 -0.3048)
							(mid 0.275042 -0.275042)
							(end 0.3048 -0.2032)
						)
					)
					(width 0)
					(fill yes)
				)
			)
		)
	)
	(footprint ""
		(layer "B.Cu")
		(at 81.76387 -48.653446 -90)
		(property "Reference" "C25"
			(at 0 0 90)
			(layer "B.SilkS")
			(hide yes)
			(effects
				(font
					(size 1.27 1.27)
				)
				(justify mirror)
			)
		)
		(property "Value" "SC2D2U25V5KX-2-GP"
			(at 0.0762 -6.1214 270)
			(unlocked yes)
			(layer "B.Fab")
			(hide yes)
			(effects
				(font
					(size 1.016 1.016)
					(thickness 0.1524)
				)
				(justify mirror)
			)
		)
		(property "Device Type" "C805H54"
			(at 0.0762 -8.1534 270)
			(unlocked yes)
			(layer "B.Fab")
			(hide yes)
			(effects
				(font
					(size 1.016 1.016)
					(thickness 0.1524)
				)
				(justify mirror)
			)
		)
		(duplicate_pad_numbers_are_jumpers no)
		(fp_line
			(start -0.635 0)
			(end 0.635 0)
			(stroke
				(width 0.508)
				(type default)
			)
			(layer "B.SilkS")
		)
		(fp_rect
			(start 0.9652 1.778)
			(end -0.9652 -1.778)
			(stroke
				(width 0)
				(type default)
			)
			(fill no)
			(layer "B.CrtYd")
		)
		(fp_poly
			(pts
				(xy 0.9652 -1.778) (xy -0.9652 -1.778) (xy -0.9652 1.778) (xy 0.9652 1.778)
			)
			(stroke
				(width 0)
				(type default)
			)
			(fill no)
			(layer "B.Fab")
		)
		(pad "1" smd rect
			(at 0 -0.9652 90)
			(size 1.397 1.143)
			(layers "B.Cu" "B.Mask" "B.Paste")
			(net "P5V_STBY")
		)
		(pad "2" smd rect
			(at 0 0.9652 90)
			(size 1.397 1.143)
			(layers "B.Cu" "B.Mask" "B.Paste")
			(net "GND")
		)
	)
	(footprint ""
		(layer "B.Cu")
		(at 195.441062 -133.83895 180)
		(property "Reference" "C626"
			(at 0 0 0)
			(layer "B.SilkS")
			(hide yes)
			(effects
				(font
					(size 1.27 1.27)
				)
				(justify mirror)
			)
		)
		(property "Value" "SCD1U16V2KX-3GP"
			(at -1.1811 -2.7051 180)
			(unlocked yes)
			(layer "B.Fab")
			(hide yes)
			(effects
				(font
					(size 1.016 1.016)
					(thickness 0.1524)
				)
				(justify mirror)
			)
		)
		(property "Device Type" "C402H22"
			(at -1.1811 -4.2291 180)
			(unlocked yes)
			(layer "B.Fab")
			(hide yes)
			(effects
				(font
					(size 1.016 1.016)
					(thickness 0.1524)
				)
				(justify mirror)
			)
		)
		(duplicate_pad_numbers_are_jumpers no)
		(fp_rect
			(start 0.4318 0.9525)
			(end -0.4318 -0.9525)
			(stroke
				(width 0)
				(type default)
			)
			(fill no)
			(layer "B.CrtYd")
		)
		(fp_rect
			(start 0.4318 0.9525)
			(end -0.4318 -0.9525)
			(stroke
				(width 0)
				(type default)
			)
			(fill no)
			(layer "B.Fab")
		)
		(pad "1" smd custom
			(at 0 -0.4445)
			(size 0.1524 0.1524)
			(layers "B.Cu" "B.Mask" "B.Paste")
			(net "P3V3_M2")
			(options
				(clearance outline)
				(anchor circle)
			)
			(primitives
				(gr_poly
					(pts
						(arc
							(start 0.3048 0.2032)
							(mid 0.275042 0.275042)
							(end 0.2032 0.3048)
						)
						(arc
							(start -0.2032 0.3048)
							(mid -0.275042 0.275042)
							(end -0.3048 0.2032)
						)
						(arc
							(start -0.3048 -0.2032)
							(mid -0.275042 -0.275042)
							(end -0.2032 -0.3048)
						)
						(arc
							(start 0.2032 -0.3048)
							(mid 0.275042 -0.275042)
							(end 0.3048 -0.2032)
						)
					)
					(width 0)
					(fill yes)
				)
			)
		)
		(pad "2" smd custom
			(at 0 0.4445)
			(size 0.1524 0.1524)
			(layers "B.Cu" "B.Mask" "B.Paste")
			(net "GND")
			(options
				(clearance outline)
				(anchor circle)
			)
			(primitives
				(gr_poly
					(pts
						(arc
							(start 0.3048 0.2032)
							(mid 0.275042 0.275042)
							(end 0.2032 0.3048)
						)
						(arc
							(start -0.2032 0.3048)
							(mid -0.275042 0.275042)
							(end -0.3048 0.2032)
						)
						(arc
							(start -0.3048 -0.2032)
							(mid -0.275042 -0.275042)
							(end -0.2032 -0.3048)
						)
						(arc
							(start 0.2032 -0.3048)
							(mid 0.275042 -0.275042)
							(end 0.3048 -0.2032)
						)
					)
					(width 0)
					(fill yes)
				)
			)
		)
	)
)
